1
1
2
2
3
3
4
4
D D
C C
B B
A A
Title
Number RevisionSize
A
Date: 12/21/2022 Sheet   of
File: C:\Users\<user>\Table_of_Contents.SchDocDrawn By:
01. Table of Contents
02. ZED-F9T
03. Antenna Supervisor Circuit



1
1
2
2
3
3
4
4
D D
C C
B B
A A
Title
Number RevisionSize
A
Date: 12/21/2022 Sheet   of
File: C:\Users\<user>\ZED-F9T.SchDoc Drawn By:
R7
10k
1 2
3 4
5 6
7 8
J1
NRPN042MAMS-RC
VCC_ANT VCC
TXD_OUT RST
RXD_IN TP1
TP2
71
U2A
SN74LVC3G07DCUR
53
U2B
SN74LVC3G07DCUR
26
U2C
SN74LVC3G07DCUR
GND 4VCC8
U2D
SN74LVC3G07DCUR
VCC
C6
100nF
VCC34 VCC33
V_BCKP36
V_USB38
RESET_N49
SAFEBOOT_N50
GND 14
GND 1
GND 3
GND 12
GND 32
GND 37
GND 41
GND 48
GND 55
U1A
ZED-F9T-00B
VCC_RF 7RF_IN2
ANT_DETECT4
ANT_OFF5
ANT_SHORT_N6
GEOFENCE_STAT 19
U1B
ZED-F9T-00B
D_SEL47 TIMEPULSE 53
TIMEPULSE2 54
RXD226 TXD227
USB_DM39
USB_DP40
TXD/SPI_MISO42
RXD/SPI_MOSI43
SDA/SPI_CS_N44
SCL/SPI_CLK45
EXTIN51
EXTIN252
U1C
ZED-F9T-00B
VCC
RST
±10%
25V
1µF
C2
VCC
±10%
25V
1µF
C3
TP1
TP1
TP2
TXD
RXD
±10%
25V
1µF
C5
R1
1k
VCC
TP2
TP3
TP5
TP4
TP6
TP7
RF_IN
ANT_OFF
ANT_DET
ANT_SHORT_N
TP8Green
DS2
VCC
Green
DS3
VCC_ANT
R8
10k
8-Position Connector
Buffer
Power Indicator LEDs
ZED-F9T GNSS Receiver
±10%
25V
1µF
C1
±10%
25V
1µF
C4
RESET_N has 
internal pull-up
RXD_IN RXD
TXD TXD_OUT
Buffer Bypass Resistors
R5
10k
R6
10k
TXD
RXD_IN
TXD_OUT
RXD
Green
DS1
R4
10k
TP2
TP2 Indicator LED
R2
1k
VCC
RXD
VCC
R3
1k
TXD_OUT
Buffer Pullups
PIC101 
PIC102 
COC1 
PIC201 
PIC202 
COC2 
PIC301 
PIC302 
COC3 PIC401 
PIC402 
COC4 
PIC501 
PIC502 
COC5 
PIC601 
PIC602 
COC6 
PIDS10A 
PIDS10K 
CODS1 
PIDS20A 
PIDS20K 
CODS2 
PIDS30A 
PIDS30K 
CODS3 
PIJ101 PIJ102 
PIJ103 PIJ104 
PIJ105 PIJ106 
PIJ107 PIJ108 
COJ1 
PIR101 
PIR102 COR1 
PIR201 
PIR202 COR2 
PIR301 
PIR302 COR3 
PIR401 
PIR402 
COR4 
PIR501 PIR502 
COR5 
PIR601 PIR602 
COR6 
PIR701 
PIR702 
COR7 
PIR801 
PIR802 
COR8 
PITP101 
COTP1 
PITP201 
COTP2 
PITP301 
COTP3 
PITP401 
COTP4 
PITP501 
COTP5 
PITP601 
COTP6 
PITP701 
COTP7 
PITP801 
COTP8 
PIU101 
PIU103 
PIU1012 
PIU1014 
PIU1032 
PIU1033 
PIU1034 
PIU1036 
PIU1037 
PIU1038 PIU1041 
PIU1048 
PIU1049 
PIU1050 PIU1055 
COU1A 
PIU102 
PIU104 
PIU105 
PIU106 
PIU107 
PIU1019 
COU1B 
PIU1026 
PIU1027 
PIU1039 
PIU1040 
PIU1042 
PIU1043 
PIU1044 
PIU1045 
PIU1047 
PIU1051 
PIU1052 
PIU1053 
PIU1054 
COU1C 
PIU201 PIU207 
COU2A 
PIU203 PIU205 
COU2B 
PIU202 PIU206 
COU2C 
PIU204 PIU208 
COU2D 
PIU104 
NLANT0DET 
PIU105 
NLANT0OFF 
PIU106 
NLANT0SHORT0N 
PIC102 PIC202 
PIC302 PIC402 
PIC502 
PIC602 
PIJ108 
PIR401 
PIR701 PIR801 
PIU101 
PIU103 
PIU1012 
PIU1014 
PIU1032 
PIU1037 
PIU1038 PIU1041 
PIU1048 
PIU1055 
PIU204 
PIC501 
PIR101 
PIU1047 
PIDS10K 
PIR402 
PIDS20K 
PIR702 
PIDS30K 
PIR802 
PITP101 
PIU1050 
PITP201 PIU1051 
PITP301 PIU1052 
PITP401 PIU1044 
PITP501 PIU1045 
PITP601 PIU1027 
PITP701 PIU1026 
PITP801 PIU1019 
PIU107 
PIU1039 
PIU1040 
PIU202 PIU206 
PIU102 
NLRF0IN 
PIJ104 PIU1049 
NLRST 
PIR201 
PIR501 
PIU1043 
PIU207 
NLRXD 
PIJ105 
PIR502 
PIU201 
NLRXD0IN 
PIJ106 
PIU1053 
NLTP1 
PIDS10A 
PIJ107 
PIU1054 
NLTP2 
PIR602 
PIU1042 
PIU203 
NLTXD 
PIJ103 
PIR301 
PIR601 
PIU205 
NLTXD0OUT 
PIC101 PIC201 
PIC301 PIC401 
PIC601 
PIDS20A 
PIJ102 
PIR102 
PIR202 PIR302 
PIU1033 
PIU1034 
PIU1036 
PIU208 
PIDS30A 
PIJ101 



1
1
2
2
3
3
4
4
D D
C C
B B
A A
Title
Number RevisionSize
A
Date: 12/21/2022 Sheet   of
File: C:\Users\<user>\Antenna_Supervisor.SchDocDrawn By:
2
1
3
NTR2101PT1G
Q1
R10
1k
R11
100k
L1
47nH 300mA
D1
PESD0402-140
C10
10nF
VCC
C7
100nF
R9
100k
VCC_ANT
GND 4VCC8
U3D
SN74LVC3G07DCUR
C9
100nF
VCC
ANT_OFF
ANT_DET
ANT_SHORT_N
Antenna Supervisor
RF_IN
C8
100nF
ANT_OFF (active high): pin is low 
to enable an external antenna.
High-side 
Switch
25
1.5W
±2%
R12
Buffer
Bias tee
RF_ANT
iRF
26
U3C
SN74LVC3G07DCUR
71
U3A
SN74LVC3G07DCUR
53
U3B
SN74LVC3G07DCUR
1
2
3
J2
SMB_131-3711-301
R13
1k
R14
1k
ANT_DET ANT_SHORT_N
VCC VCC
Buffer Pullups
2
3
4
5
1
U4
LPV511MGX/NOPB
PIC701 
PIC702 
COC7 
PIC801 
PIC802 
COC8 
PIC901 
PIC902 
COC9 PIC1001 
PIC1002 
COC10 
PID101 
PID102 
COD1 
PIJ201 
PIJ202 
PIJ203 
COJ2 
PIL101 PIL102 
COL1 
PIQ101 
PIQ102 PIQ103 
COQ1 
PIR901 
PIR902 COR9 
PIR1001 
PIR1002 COR10 
PIR1101 
PIR1102 COR11 
PIR1201 
PIR1202 
COR12 
PIR1301 
PIR1302 
COR13 
PIR1401 
PIR1402 
COR14 
PIU301 PIU307 
COU3A 
PIU303 PIU305 
COU3B 
PIU302 PIU306 
COU3C 
PIU304 PIU308 
COU3D 
PIU401 
PIU402 
PIU403 
PIU404 
PIU405 COU4 
PIR1301 
PIU307 
NLANT0DET 
PIU306 
NLANT0OFF 
PIR1401 
PIU305 
NLANT0SHORT0N 
PIC702 
PIC902 
PIC1002 
PID101 
PIJ202 
PIJ203 
PIR1101 
PIU304 
PIU402 
PIC1001 
PIL101 
PIR1202 
PIU303 
PIU404 
PIQ101 
PIR901 
PIU302 
PIQ103 
PIR1002 
PIR1201 
PIR1001 
PIR1102 
PIU403 
PIU301 PIU401 
PIC802 
PID102 
PIJ201 PIL102 
NLRF0ANT 
PIC801 
NLRF0IN 
PIC701 
PIC901 
PIR1302 PIR1402 
PIU308 
PIU405 
PIQ102 
PIR902 